(kicad_pcb
	(version 20260206)
	(generator "pcbnew")
	(generator_version "10.0")
	(general
		(thickness 1.6)
		(legacy_teardrops no)
	)
	(paper "A4")
	(title_block
		(title "03242023_DA0F0TMBIJ0_F0T_Motherboard_J_brd_V01_OCP.brd")
		(comment 1 "Grand Teton / footprint 501 of 6105 (J22), pads 225-291 of 291")
	)
	(layers
		(0 "F.Cu" signal "TOP")
		(4 "In1.Cu" signal "GND")
		(6 "In2.Cu" signal "IN1")
		(8 "In3.Cu" signal "GND1")
		(10 "In4.Cu" signal "IN2")
		(12 "In5.Cu" signal "GND2")
		(14 "In6.Cu" signal "IN3")
		(16 "In7.Cu" signal "GND3")
		(18 "In8.Cu" signal "VCC")
		(20 "In9.Cu" signal "VCC1")
		(22 "In10.Cu" signal "GND4")
		(24 "In11.Cu" signal "IN4")
		(26 "In12.Cu" signal "GND5")
		(28 "In13.Cu" signal "IN5")
		(30 "In14.Cu" signal "GND6")
		(32 "In15.Cu" signal "IN6")
		(34 "In16.Cu" signal "GND7")
		(2 "B.Cu" signal "BOTTOM")
		(9 "F.Adhes" user "F.Adhesive")
		(11 "B.Adhes" user "B.Adhesive")
		(13 "F.Paste" user "Package Geometry/Pastemask Top")
		(15 "B.Paste" user "Package Geometry/Pastemask Bottom")
		(5 "F.SilkS" user "Ref Des/Silkscreen Top")
		(7 "B.SilkS" user "Ref Des/Silkscreen Bottom")
		(1 "F.Mask" user "Board Geometry/Soldermask Top")
		(3 "B.Mask" user "Board Geometry/Soldermask Bottom")
		(17 "Dwgs.User" user "User.Drawings")
		(19 "Cmts.User" user "User.Comments")
		(21 "Eco1.User" user "User.Eco1")
		(23 "Eco2.User" user "User.Eco2")
		(25 "Edge.Cuts" user "Board Geometry/Outline")
		(27 "Margin" user)
		(31 "F.CrtYd" user "Package Geometry/Place Bound Top")
		(29 "B.CrtYd" user "Package Geometry/Place Bound Bottom")
		(35 "F.Fab" user "Ref Des/Assembly Top")
		(33 "B.Fab" user "Ref Des/Assembly Bottom")
	)
	(footprint ""
		(layer "F.Cu")
		(at 32.82188 -258.091686)
		(property "Reference" "J22"
			(at -1.420622 -81.912714 0)
			(unlocked yes)
			(layer "F.SilkS")
			(effects
				(font
					(size 0.7874 0.5842)
					(thickness 0.1524)
				)
				(justify left)
			)
		)
		(property "Value" ""
			(at 0 0 0)
			(layer "F.Fab")
			(effects
				(font
					(size 1.27 1.27)
				)
			)
		)
		(duplicate_pad_numbers_are_jumpers no)
		(pad "225" smd rect
			(at 2.050034 9.774936 270)
			(size 0.519938 1.4986)
			(layers "F.Cu" "F.Mask" "F.Paste")
			(net "M_C_CPU1_SB_CA<5>")
		)
		(pad "226" smd rect
			(at 2.050034 10.625074 270)
			(size 0.519938 1.4986)
			(layers "F.Cu" "F.Mask" "F.Paste")
			(net "GND")
		)
		(pad "227" smd rect
			(at 2.050034 11.474958 270)
			(size 0.519938 1.4986)
			(layers "F.Cu" "F.Mask" "F.Paste")
			(net "M_C_CPU1_SB_PAR")
		)
		(pad "228" smd rect
			(at 2.050034 12.325096 270)
			(size 0.519938 1.4986)
			(layers "F.Cu" "F.Mask" "F.Paste")
			(net "GND")
		)
		(pad "229" smd rect
			(at 2.050034 13.17498 270)
			(size 0.519938 1.4986)
			(layers "F.Cu" "F.Mask" "F.Paste")
			(net "M_C_CPU1_SB_CS_N<3>")
		)
		(pad "230" smd rect
			(at 2.050034 14.025118 270)
			(size 0.519938 1.4986)
			(layers "F.Cu" "F.Mask" "F.Paste")
			(net "GND")
		)
		(pad "231" smd rect
			(at 2.050034 14.875002 270)
			(size 0.519938 1.4986)
			(layers "F.Cu" "F.Mask" "F.Paste")
			(net "TP_CHC_CPU1_DIMM2_FRU_5")
		)
		(pad "232" smd rect
			(at 2.050034 15.724886 270)
			(size 0.519938 1.4986)
			(layers "F.Cu" "F.Mask" "F.Paste")
			(net "TP_CHC_CPU1_DIMM2_FRU_6")
		)
		(pad "233" smd rect
			(at 2.050034 16.575024 270)
			(size 0.519938 1.4986)
			(layers "F.Cu" "F.Mask" "F.Paste")
			(net "GND")
		)
		(pad "234" smd rect
			(at 2.050034 17.424908 270)
			(size 0.519938 1.4986)
			(layers "F.Cu" "F.Mask" "F.Paste")
			(net "M_C_CPU1_SB_CB<6>")
		)
		(pad "235" smd rect
			(at 2.050034 18.275046 270)
			(size 0.519938 1.4986)
			(layers "F.Cu" "F.Mask" "F.Paste")
			(net "GND")
		)
		(pad "236" smd rect
			(at 2.050034 19.12493 270)
			(size 0.519938 1.4986)
			(layers "F.Cu" "F.Mask" "F.Paste")
			(net "M_C_CPU1_SB_CB<7>")
		)
		(pad "237" smd rect
			(at 2.050034 19.975068 270)
			(size 0.519938 1.4986)
			(layers "F.Cu" "F.Mask" "F.Paste")
			(net "GND")
		)
		(pad "238" smd rect
			(at 2.050034 20.824952 270)
			(size 0.519938 1.4986)
			(layers "F.Cu" "F.Mask" "F.Paste")
			(net "M_C_CPU1_SB_DQS_DN<4>")
		)
		(pad "239" smd rect
			(at 2.050034 21.67509 270)
			(size 0.519938 1.4986)
			(layers "F.Cu" "F.Mask" "F.Paste")
			(net "M_C_CPU1_SB_DQS_DP<4>")
		)
		(pad "240" smd rect
			(at 2.050034 22.524974 270)
			(size 0.519938 1.4986)
			(layers "F.Cu" "F.Mask" "F.Paste")
			(net "GND")
		)
		(pad "241" smd rect
			(at 2.050034 23.375112 270)
			(size 0.519938 1.4986)
			(layers "F.Cu" "F.Mask" "F.Paste")
			(net "M_C_CPU1_SB_CB<2>")
		)
		(pad "242" smd rect
			(at 2.050034 24.224996 270)
			(size 0.519938 1.4986)
			(layers "F.Cu" "F.Mask" "F.Paste")
			(net "GND")
		)
		(pad "243" smd rect
			(at 2.050034 25.07488 270)
			(size 0.519938 1.4986)
			(layers "F.Cu" "F.Mask" "F.Paste")
			(net "M_C_CPU1_SB_CB<3>")
		)
		(pad "244" smd rect
			(at 2.050034 25.925018 270)
			(size 0.519938 1.4986)
			(layers "F.Cu" "F.Mask" "F.Paste")
			(net "GND")
		)
		(pad "245" smd rect
			(at 2.050034 26.774902 270)
			(size 0.519938 1.4986)
			(layers "F.Cu" "F.Mask" "F.Paste")
			(net "M_C_CPU1_SB_DQ<2>")
		)
		(pad "246" smd rect
			(at 2.050034 27.62504 270)
			(size 0.519938 1.4986)
			(layers "F.Cu" "F.Mask" "F.Paste")
			(net "GND")
		)
		(pad "247" smd rect
			(at 2.050034 28.474924 270)
			(size 0.519938 1.4986)
			(layers "F.Cu" "F.Mask" "F.Paste")
			(net "M_C_CPU1_SB_DQ<3>")
		)
		(pad "248" smd rect
			(at 2.050034 29.325062 270)
			(size 0.519938 1.4986)
			(layers "F.Cu" "F.Mask" "F.Paste")
			(net "GND")
		)
		(pad "249" smd rect
			(at 2.050034 30.174946 270)
			(size 0.519938 1.4986)
			(layers "F.Cu" "F.Mask" "F.Paste")
			(net "M_C_CPU1_SB_DQS_DN<5>")
		)
		(pad "250" smd rect
			(at 2.050034 31.025084 270)
			(size 0.519938 1.4986)
			(layers "F.Cu" "F.Mask" "F.Paste")
			(net "M_C_CPU1_SB_DQS_DP<5>")
		)
		(pad "251" smd rect
			(at 2.050034 31.874968 270)
			(size 0.519938 1.4986)
			(layers "F.Cu" "F.Mask" "F.Paste")
			(net "GND")
		)
		(pad "252" smd rect
			(at 2.050034 32.725106 270)
			(size 0.519938 1.4986)
			(layers "F.Cu" "F.Mask" "F.Paste")
			(net "M_C_CPU1_SB_DQ<6>")
		)
		(pad "253" smd rect
			(at 2.050034 33.57499 270)
			(size 0.519938 1.4986)
			(layers "F.Cu" "F.Mask" "F.Paste")
			(net "GND")
		)
		(pad "254" smd rect
			(at 2.050034 34.425128 270)
			(size 0.519938 1.4986)
			(layers "F.Cu" "F.Mask" "F.Paste")
			(net "M_C_CPU1_SB_DQ<7>")
		)
		(pad "255" smd rect
			(at 2.050034 35.275012 270)
			(size 0.519938 1.4986)
			(layers "F.Cu" "F.Mask" "F.Paste")
			(net "GND")
		)
		(pad "256" smd rect
			(at 2.050034 36.124896 270)
			(size 0.519938 1.4986)
			(layers "F.Cu" "F.Mask" "F.Paste")
			(net "M_C_CPU1_SB_DQ<10>")
		)
		(pad "257" smd rect
			(at 2.050034 36.975034 270)
			(size 0.519938 1.4986)
			(layers "F.Cu" "F.Mask" "F.Paste")
			(net "GND")
		)
		(pad "258" smd rect
			(at 2.050034 37.824918 270)
			(size 0.519938 1.4986)
			(layers "F.Cu" "F.Mask" "F.Paste")
			(net "M_C_CPU1_SB_DQ<11>")
		)
		(pad "259" smd rect
			(at 2.050034 38.675056 270)
			(size 0.519938 1.4986)
			(layers "F.Cu" "F.Mask" "F.Paste")
			(net "GND")
		)
		(pad "260" smd rect
			(at 2.050034 39.52494 270)
			(size 0.519938 1.4986)
			(layers "F.Cu" "F.Mask" "F.Paste")
			(net "M_C_CPU1_SB_DQS_DN<6>")
		)
		(pad "261" smd rect
			(at 2.050034 40.375078 270)
			(size 0.519938 1.4986)
			(layers "F.Cu" "F.Mask" "F.Paste")
			(net "M_C_CPU1_SB_DQS_DP<6>")
		)
		(pad "262" smd rect
			(at 2.050034 41.224962 270)
			(size 0.519938 1.4986)
			(layers "F.Cu" "F.Mask" "F.Paste")
			(net "GND")
		)
		(pad "263" smd rect
			(at 2.050034 42.0751 270)
			(size 0.519938 1.4986)
			(layers "F.Cu" "F.Mask" "F.Paste")
			(net "M_C_CPU1_SB_DQ<14>")
		)
		(pad "264" smd rect
			(at 2.050034 42.924984 270)
			(size 0.519938 1.4986)
			(layers "F.Cu" "F.Mask" "F.Paste")
			(net "GND")
		)
		(pad "265" smd rect
			(at 2.050034 43.775122 270)
			(size 0.519938 1.4986)
			(layers "F.Cu" "F.Mask" "F.Paste")
			(net "M_C_CPU1_SB_DQ<15>")
		)
		(pad "266" smd rect
			(at 2.050034 44.625006 270)
			(size 0.519938 1.4986)
			(layers "F.Cu" "F.Mask" "F.Paste")
			(net "GND")
		)
		(pad "267" smd rect
			(at 2.050034 45.47489 270)
			(size 0.519938 1.4986)
			(layers "F.Cu" "F.Mask" "F.Paste")
			(net "M_C_CPU1_SB_DQ<18>")
		)
		(pad "268" smd rect
			(at 2.050034 46.325028 270)
			(size 0.519938 1.4986)
			(layers "F.Cu" "F.Mask" "F.Paste")
			(net "GND")
		)
		(pad "269" smd rect
			(at 2.050034 47.174912 270)
			(size 0.519938 1.4986)
			(layers "F.Cu" "F.Mask" "F.Paste")
			(net "M_C_CPU1_SB_DQ<19>")
		)
		(pad "270" smd rect
			(at 2.050034 48.02505 270)
			(size 0.519938 1.4986)
			(layers "F.Cu" "F.Mask" "F.Paste")
			(net "GND")
		)
		(pad "271" smd rect
			(at 2.050034 48.874934 270)
			(size 0.519938 1.4986)
			(layers "F.Cu" "F.Mask" "F.Paste")
			(net "M_C_CPU1_SB_DQS_DN<7>")
		)
		(pad "272" smd rect
			(at 2.050034 49.725072 270)
			(size 0.519938 1.4986)
			(layers "F.Cu" "F.Mask" "F.Paste")
			(net "M_C_CPU1_SB_DQS_DP<7>")
		)
		(pad "273" smd rect
			(at 2.050034 50.574956 270)
			(size 0.519938 1.4986)
			(layers "F.Cu" "F.Mask" "F.Paste")
			(net "GND")
		)
		(pad "274" smd rect
			(at 2.050034 51.425094 270)
			(size 0.519938 1.4986)
			(layers "F.Cu" "F.Mask" "F.Paste")
			(net "M_C_CPU1_SB_DQ<22>")
		)
		(pad "275" smd rect
			(at 2.050034 52.274978 270)
			(size 0.519938 1.4986)
			(layers "F.Cu" "F.Mask" "F.Paste")
			(net "GND")
		)
		(pad "276" smd rect
			(at 2.050034 53.125116 270)
			(size 0.519938 1.4986)
			(layers "F.Cu" "F.Mask" "F.Paste")
			(net "M_C_CPU1_SB_DQ<23>")
		)
		(pad "277" smd rect
			(at 2.050034 53.975 270)
			(size 0.519938 1.4986)
			(layers "F.Cu" "F.Mask" "F.Paste")
			(net "GND")
		)
		(pad "278" smd rect
			(at 2.050034 54.824884 270)
			(size 0.519938 1.4986)
			(layers "F.Cu" "F.Mask" "F.Paste")
			(net "M_C_CPU1_SB_DQ<26>")
		)
		(pad "279" smd rect
			(at 2.050034 55.675022 270)
			(size 0.519938 1.4986)
			(layers "F.Cu" "F.Mask" "F.Paste")
			(net "GND")
		)
		(pad "280" smd rect
			(at 2.050034 56.524906 270)
			(size 0.519938 1.4986)
			(layers "F.Cu" "F.Mask" "F.Paste")
			(net "M_C_CPU1_SB_DQ<27>")
		)
		(pad "281" smd rect
			(at 2.050034 57.375044 270)
			(size 0.519938 1.4986)
			(layers "F.Cu" "F.Mask" "F.Paste")
			(net "GND")
		)
		(pad "282" smd rect
			(at 2.050034 58.224928 270)
			(size 0.519938 1.4986)
			(layers "F.Cu" "F.Mask" "F.Paste")
			(net "M_C_CPU1_SB_DQS_DN<8>")
		)
		(pad "283" smd rect
			(at 2.050034 59.075066 270)
			(size 0.519938 1.4986)
			(layers "F.Cu" "F.Mask" "F.Paste")
			(net "M_C_CPU1_SB_DQS_DP<8>")
		)
		(pad "284" smd rect
			(at 2.050034 59.92495 270)
			(size 0.519938 1.4986)
			(layers "F.Cu" "F.Mask" "F.Paste")
			(net "GND")
		)
		(pad "285" smd rect
			(at 2.050034 60.775088 270)
			(size 0.519938 1.4986)
			(layers "F.Cu" "F.Mask" "F.Paste")
			(net "M_C_CPU1_SB_DQ<30>")
		)
		(pad "286" smd rect
			(at 2.050034 61.624972 270)
			(size 0.519938 1.4986)
			(layers "F.Cu" "F.Mask" "F.Paste")
			(net "GND")
		)
		(pad "287" smd rect
			(at 2.050034 62.47511 270)
			(size 0.519938 1.4986)
			(layers "F.Cu" "F.Mask" "F.Paste")
			(net "M_C_CPU1_SB_DQ<31>")
		)
		(pad "288" smd rect
			(at 2.050034 63.324994 270)
			(size 0.519938 1.4986)
			(layers "F.Cu" "F.Mask" "F.Paste")
			(net "GND")
		)
		(pad "G1" thru_hole oval
			(at 0 -68.97497)
			(size 2.8194 1.5748)
			(drill oval 2.4384 1.1938)
			(layers "*.Cu" "*.Mask")
			(remove_unused_layers no)
			(net "GND")
			(clearance 0.127)
			(thermal_gap 0.127)
		)
		(pad "G2" thru_hole oval
			(at 0 3.875024)
			(size 2.8194 1.5748)
			(drill oval 2.4384 1.1938)
			(layers "*.Cu" "*.Mask")
			(remove_unused_layers no)
			(net "GND")
			(clearance 0.127)
			(thermal_gap 0.127)
		)
		(pad "G3" thru_hole oval
			(at 0 68.97497)
			(size 2.8194 1.5748)
			(drill oval 2.4384 1.1938)
			(layers "*.Cu" "*.Mask")
			(remove_unused_layers no)
			(net "GND")
			(clearance 0.127)
			(thermal_gap 0.127)
		)
	)
)
